(kicad_pcb
	(version 20260206)
	(generator "pcbnew")
	(generator_version "10.0")
	(general
		(thickness 1.6)
		(legacy_teardrops no)
	)
	(paper "A4")
	(title_block
		(title "04192023_DAF0TMB3IC0_F0TG_MB_C_brd_V02_OCP.brd")
		(comment 1 "Grand Teton / footprints 3683-3690 of 8354")
	)
	(layers
		(0 "F.Cu" signal "TOP")
		(4 "In1.Cu" signal "GND")
		(6 "In2.Cu" signal "IN1")
		(8 "In3.Cu" signal "GND1")
		(10 "In4.Cu" signal "IN2")
		(12 "In5.Cu" signal "GND2")
		(14 "In6.Cu" signal "IN3")
		(16 "In7.Cu" signal "GND3")
		(18 "In8.Cu" signal "VCC")
		(20 "In9.Cu" signal "VCC1")
		(22 "In10.Cu" signal "GND4")
		(24 "In11.Cu" signal "IN4")
		(26 "In12.Cu" signal "GND5")
		(28 "In13.Cu" signal "IN5")
		(30 "In14.Cu" signal "GND6")
		(32 "In15.Cu" signal "IN6")
		(34 "In16.Cu" signal "GND7")
		(2 "B.Cu" signal "BOTTOM")
		(9 "F.Adhes" user "F.Adhesive")
		(11 "B.Adhes" user "B.Adhesive")
		(13 "F.Paste" user "Package Geometry/Pastemask Top")
		(15 "B.Paste" user "Package Geometry/Pastemask Bottom")
		(5 "F.SilkS" user "Ref Des/Silkscreen Top")
		(7 "B.SilkS" user "Ref Des/Silkscreen Bottom")
		(1 "F.Mask" user "Board Geometry/Soldermask Top")
		(3 "B.Mask" user "Board Geometry/Soldermask Bottom")
		(17 "Dwgs.User" user "User.Drawings")
		(19 "Cmts.User" user "User.Comments")
		(21 "Eco1.User" user "User.Eco1")
		(23 "Eco2.User" user "User.Eco2")
		(25 "Edge.Cuts" user "Board Geometry/Outline")
		(27 "Margin" user)
		(31 "F.CrtYd" user "Package Geometry/Place Bound Top")
		(29 "B.CrtYd" user "Package Geometry/Place Bound Bottom")
		(35 "F.Fab" user "Ref Des/Assembly Top")
		(33 "B.Fab" user "Ref Des/Assembly Bottom")
	)
	(footprint ""
		(layer "F.Cu")
		(at 97.719642 -400.417792)
		(property "Reference" "R1215"
			(at 0 0 0)
			(layer "F.SilkS")
			(hide yes)
			(effects
				(font
					(size 1.27 1.27)
				)
			)
		)
		(property "Value" ""
			(at 0 0 0)
			(layer "F.Fab")
			(effects
				(font
					(size 1.27 1.27)
				)
			)
		)
		(duplicate_pad_numbers_are_jumpers no)
		(fp_line
			(start -0.32512 -0.175006)
			(end 0.32512 -0.175006)
			(stroke
				(width 0.1)
				(type default)
			)
			(layer "F.Fab")
		)
		(fp_line
			(start -0.32512 0.175006)
			(end -0.32512 -0.175006)
			(stroke
				(width 0.1)
				(type default)
			)
			(layer "F.Fab")
		)
		(fp_line
			(start 0.32512 -0.175006)
			(end 0.32512 0.175006)
			(stroke
				(width 0.1)
				(type default)
			)
			(layer "F.Fab")
		)
		(fp_line
			(start 0.32512 0.175006)
			(end -0.32512 0.175006)
			(stroke
				(width 0.1)
				(type default)
			)
			(layer "F.Fab")
		)
		(pad "1" smd rect
			(at -0.2667 0)
			(size 0.3048 0.381)
			(layers "F.Cu" "F.Mask" "F.Paste")
			(net "GND")
		)
		(pad "2" smd rect
			(at 0.2667 0 180)
			(size 0.3048 0.381)
			(layers "F.Cu" "F.Mask" "F.Paste")
			(net "RT_ROM_MUX1_OE_N")
		)
	)
	(footprint ""
		(layer "F.Cu")
		(at 461.593946 -108.567728)
		(property "Reference" "R1148"
			(at 0 0 0)
			(layer "F.SilkS")
			(hide yes)
			(effects
				(font
					(size 1.27 1.27)
				)
			)
		)
		(property "Value" ""
			(at 0 0 0)
			(layer "F.Fab")
			(effects
				(font
					(size 1.27 1.27)
				)
			)
		)
		(duplicate_pad_numbers_are_jumpers no)
		(fp_line
			(start -0.7874 -0.4064)
			(end 0.7874 -0.4064)
			(stroke
				(width 0.1524)
				(type default)
			)
			(layer "F.SilkS")
		)
		(fp_line
			(start -0.7874 0.4064)
			(end -0.7874 -0.4064)
			(stroke
				(width 0.1524)
				(type default)
			)
			(layer "F.SilkS")
		)
		(fp_line
			(start 0.7874 -0.4064)
			(end 0.7874 0.4064)
			(stroke
				(width 0.1524)
				(type default)
			)
			(layer "F.SilkS")
		)
		(fp_line
			(start 0.7874 0.4064)
			(end -0.7874 0.4064)
			(stroke
				(width 0.1524)
				(type default)
			)
			(layer "F.SilkS")
		)
		(fp_line
			(start -0.67945 -0.305054)
			(end -0.12065 -0.305054)
			(stroke
				(width 0.1)
				(type default)
			)
			(layer "F.Fab")
		)
		(fp_line
			(start -0.67945 0.3048)
			(end -0.67945 -0.305054)
			(stroke
				(width 0.1)
				(type default)
			)
			(layer "F.Fab")
		)
		(fp_line
			(start -0.12065 -0.305054)
			(end -0.12065 -0.2794)
			(stroke
				(width 0.1)
				(type default)
			)
			(layer "F.Fab")
		)
		(fp_line
			(start -0.12065 -0.2794)
			(end 0.12065 -0.2794)
			(stroke
				(width 0.1)
				(type default)
			)
			(layer "F.Fab")
		)
		(fp_line
			(start -0.12065 0.2794)
			(end -0.12065 0.3048)
			(stroke
				(width 0.1)
				(type default)
			)
			(layer "F.Fab")
		)
		(fp_line
			(start -0.12065 0.3048)
			(end -0.67945 0.3048)
			(stroke
				(width 0.1)
				(type default)
			)
			(layer "F.Fab")
		)
		(fp_line
			(start 0.120396 0.2794)
			(end -0.12065 0.2794)
			(stroke
				(width 0.1)
				(type default)
			)
			(layer "F.Fab")
		)
		(fp_line
			(start 0.120396 0.3048)
			(end 0.120396 0.2794)
			(stroke
				(width 0.1)
				(type default)
			)
			(layer "F.Fab")
		)
		(fp_line
			(start 0.12065 -0.3048)
			(end 0.67945 -0.3048)
			(stroke
				(width 0.1)
				(type default)
			)
			(layer "F.Fab")
		)
		(fp_line
			(start 0.12065 -0.2794)
			(end 0.12065 -0.3048)
			(stroke
				(width 0.1)
				(type default)
			)
			(layer "F.Fab")
		)
		(fp_line
			(start 0.67945 -0.3048)
			(end 0.67945 0.3048)
			(stroke
				(width 0.1)
				(type default)
			)
			(layer "F.Fab")
		)
		(fp_line
			(start 0.67945 0.3048)
			(end 0.120396 0.3048)
			(stroke
				(width 0.1)
				(type default)
			)
			(layer "F.Fab")
		)
		(pad "1" smd circle
			(at -0.40005 0)
			(size 0 0)
			(layers "F.Cu" "F.Mask" "F.Paste")
			(net "HP_LVC3_OCP_V3_1_PRSNT2_N_R")
		)
		(pad "2" smd circle
			(at 0.40005 0)
			(size 0 0)
			(layers "F.Cu" "F.Mask" "F.Paste")
			(net "HP_LVC3_OCP_SFF_PRSNT2_PLD_N")
		)
	)
	(footprint ""
		(layer "F.Cu")
		(at 131.664964 -151.8793 -90)
		(property "Reference" "PR215"
			(at 0 0 270)
			(layer "F.SilkS")
			(hide yes)
			(effects
				(font
					(size 1.27 1.27)
				)
			)
		)
		(property "Value" ""
			(at 0 0 270)
			(layer "F.Fab")
			(effects
				(font
					(size 1.27 1.27)
				)
			)
		)
		(duplicate_pad_numbers_are_jumpers no)
		(fp_line
			(start -0.7874 0.4064)
			(end -0.7874 -0.4064)
			(stroke
				(width 0.1524)
				(type default)
			)
			(layer "F.SilkS")
		)
		(fp_line
			(start 0.7874 0.4064)
			(end -0.7874 0.4064)
			(stroke
				(width 0.1524)
				(type default)
			)
			(layer "F.SilkS")
		)
		(fp_line
			(start -0.7874 -0.4064)
			(end 0.7874 -0.4064)
			(stroke
				(width 0.1524)
				(type default)
			)
			(layer "F.SilkS")
		)
		(fp_line
			(start 0.7874 -0.4064)
			(end 0.7874 0.4064)
			(stroke
				(width 0.1524)
				(type default)
			)
			(layer "F.SilkS")
		)
		(fp_line
			(start -0.67945 0.3048)
			(end -0.67945 -0.305054)
			(stroke
				(width 0.1)
				(type default)
			)
			(layer "F.Fab")
		)
		(fp_line
			(start -0.12065 0.3048)
			(end -0.67945 0.3048)
			(stroke
				(width 0.1)
				(type default)
			)
			(layer "F.Fab")
		)
		(fp_line
			(start 0.120396 0.3048)
			(end 0.120396 0.2794)
			(stroke
				(width 0.1)
				(type default)
			)
			(layer "F.Fab")
		)
		(fp_line
			(start 0.67945 0.3048)
			(end 0.120396 0.3048)
			(stroke
				(width 0.1)
				(type default)
			)
			(layer "F.Fab")
		)
		(fp_line
			(start -0.12065 0.2794)
			(end -0.12065 0.3048)
			(stroke
				(width 0.1)
				(type default)
			)
			(layer "F.Fab")
		)
		(fp_line
			(start 0.120396 0.2794)
			(end -0.12065 0.2794)
			(stroke
				(width 0.1)
				(type default)
			)
			(layer "F.Fab")
		)
		(fp_line
			(start -0.12065 -0.2794)
			(end 0.12065 -0.2794)
			(stroke
				(width 0.1)
				(type default)
			)
			(layer "F.Fab")
		)
		(fp_line
			(start 0.12065 -0.2794)
			(end 0.12065 -0.3048)
			(stroke
				(width 0.1)
				(type default)
			)
			(layer "F.Fab")
		)
		(fp_line
			(start 0.12065 -0.3048)
			(end 0.67945 -0.3048)
			(stroke
				(width 0.1)
				(type default)
			)
			(layer "F.Fab")
		)
		(fp_line
			(start 0.67945 -0.3048)
			(end 0.67945 0.3048)
			(stroke
				(width 0.1)
				(type default)
			)
			(layer "F.Fab")
		)
		(fp_line
			(start -0.67945 -0.305054)
			(end -0.12065 -0.305054)
			(stroke
				(width 0.1)
				(type default)
			)
			(layer "F.Fab")
		)
		(fp_line
			(start -0.12065 -0.305054)
			(end -0.12065 -0.2794)
			(stroke
				(width 0.1)
				(type default)
			)
			(layer "F.Fab")
		)
		(pad "1" smd circle
			(at -0.40005 0 270)
			(size 0 0)
			(layers "F.Cu" "F.Mask" "F.Paste")
			(net "SW_PVDDCR_SOC_P1_BOOT3")
		)
		(pad "2" smd circle
			(at 0.40005 0 270)
			(size 0 0)
			(layers "F.Cu" "F.Mask" "F.Paste")
			(net "SW_PVDDCR_SOC_P1_BOOT3_RC")
		)
	)
	(footprint ""
		(layer "F.Cu")
		(at 71.882 -386.7912 90)
		(property "Reference" "R6713"
			(at 0 0 90)
			(layer "F.SilkS")
			(hide yes)
			(effects
				(font
					(size 1.27 1.27)
				)
			)
		)
		(property "Value" ""
			(at 0 0 90)
			(layer "F.Fab")
			(effects
				(font
					(size 1.27 1.27)
				)
			)
		)
		(duplicate_pad_numbers_are_jumpers no)
		(fp_line
			(start 0.32512 -0.175006)
			(end 0.32512 0.175006)
			(stroke
				(width 0.1)
				(type default)
			)
			(layer "F.Fab")
		)
		(fp_line
			(start -0.32512 -0.175006)
			(end 0.32512 -0.175006)
			(stroke
				(width 0.1)
				(type default)
			)
			(layer "F.Fab")
		)
		(fp_line
			(start 0.32512 0.175006)
			(end -0.32512 0.175006)
			(stroke
				(width 0.1)
				(type default)
			)
			(layer "F.Fab")
		)
		(fp_line
			(start -0.32512 0.175006)
			(end -0.32512 -0.175006)
			(stroke
				(width 0.1)
				(type default)
			)
			(layer "F.Fab")
		)
		(pad "1" smd rect
			(at -0.2667 0 90)
			(size 0.3048 0.381)
			(layers "F.Cu" "F.Mask" "F.Paste")
			(net "RT_CPU1_P0_ADDR3")
		)
		(pad "2" smd rect
			(at 0.2667 0 270)
			(size 0.3048 0.381)
			(layers "F.Cu" "F.Mask" "F.Paste")
			(net "GND")
		)
	)
	(footprint ""
		(layer "F.Cu")
		(at 445.552068 -23.64105)
		(property "Reference" "PC2082"
			(at 0 0 0)
			(layer "F.SilkS")
			(hide yes)
			(effects
				(font
					(size 1.27 1.27)
				)
			)
		)
		(property "Value" ""
			(at 0 0 0)
			(layer "F.Fab")
			(effects
				(font
					(size 1.27 1.27)
				)
			)
		)
		(duplicate_pad_numbers_are_jumpers no)
		(fp_line
			(start -1.524 -0.762)
			(end 1.524 -0.762)
			(stroke
				(width 0.1524)
				(type default)
			)
			(layer "F.SilkS")
		)
		(fp_line
			(start -1.524 0.762)
			(end -1.524 -0.762)
			(stroke
				(width 0.1524)
				(type default)
			)
			(layer "F.SilkS")
		)
		(fp_line
			(start 1.524 -0.762)
			(end 1.524 0.762)
			(stroke
				(width 0.1524)
				(type default)
			)
			(layer "F.SilkS")
		)
		(fp_line
			(start 1.524 0.762)
			(end -1.524 0.762)
			(stroke
				(width 0.1524)
				(type default)
			)
			(layer "F.SilkS")
		)
		(fp_line
			(start -1.1049 -0.724916)
			(end -1.1049 0.724916)
			(stroke
				(width 0.1)
				(type default)
			)
			(layer "F.Fab")
		)
		(fp_line
			(start -1.1049 0.724916)
			(end 1.1049 0.724916)
			(stroke
				(width 0.1)
				(type default)
			)
			(layer "F.Fab")
		)
		(fp_line
			(start 1.1049 -0.724916)
			(end -1.1049 -0.724916)
			(stroke
				(width 0.1)
				(type default)
			)
			(layer "F.Fab")
		)
		(fp_line
			(start 1.1049 0.724916)
			(end 1.1049 -0.724916)
			(stroke
				(width 0.1)
				(type default)
			)
			(layer "F.Fab")
		)
		(pad "1" smd rect
			(at -0.889 0 180)
			(size 1.016 1.27)
			(layers "F.Cu" "F.Mask" "F.Paste")
			(net "P12V_OCP_SFF")
		)
		(pad "2" smd rect
			(at 0.889 0 180)
			(size 1.016 1.27)
			(layers "F.Cu" "F.Mask" "F.Paste")
			(net "GND")
		)
	)
	(footprint ""
		(layer "F.Cu")
		(at 108.521754 -327.074276 90)
		(property "Reference" "PC392"
			(at 0 0 90)
			(layer "F.SilkS")
			(hide yes)
			(effects
				(font
					(size 1.27 1.27)
				)
			)
		)
		(property "Value" ""
			(at 0 0 90)
			(layer "F.Fab")
			(effects
				(font
					(size 1.27 1.27)
				)
			)
		)
		(duplicate_pad_numbers_are_jumpers no)
		(fp_line
			(start 0.7874 -0.4064)
			(end 0.7874 0.4064)
			(stroke
				(width 0.1524)
				(type default)
			)
			(layer "F.SilkS")
		)
		(fp_line
			(start -0.7874 -0.4064)
			(end 0.7874 -0.4064)
			(stroke
				(width 0.1524)
				(type default)
			)
			(layer "F.SilkS")
		)
		(fp_line
			(start 0.7874 0.4064)
			(end -0.7874 0.4064)
			(stroke
				(width 0.1524)
				(type default)
			)
			(layer "F.SilkS")
		)
		(fp_line
			(start -0.7874 0.4064)
			(end -0.7874 -0.4064)
			(stroke
				(width 0.1524)
				(type default)
			)
			(layer "F.SilkS")
		)
		(fp_line
			(start -0.12065 -0.305054)
			(end -0.12065 -0.2794)
			(stroke
				(width 0.1)
				(type default)
			)
			(layer "F.Fab")
		)
		(fp_line
			(start -0.67945 -0.305054)
			(end -0.12065 -0.305054)
			(stroke
				(width 0.1)
				(type default)
			)
			(layer "F.Fab")
		)
		(fp_line
			(start 0.67945 -0.3048)
			(end 0.67945 0.3048)
			(stroke
				(width 0.1)
				(type default)
			)
			(layer "F.Fab")
		)
		(fp_line
			(start 0.12065 -0.3048)
			(end 0.67945 -0.3048)
			(stroke
				(width 0.1)
				(type default)
			)
			(layer "F.Fab")
		)
		(fp_line
			(start 0.12065 -0.2794)
			(end 0.12065 -0.3048)
			(stroke
				(width 0.1)
				(type default)
			)
			(layer "F.Fab")
		)
		(fp_line
			(start -0.12065 -0.2794)
			(end 0.12065 -0.2794)
			(stroke
				(width 0.1)
				(type default)
			)
			(layer "F.Fab")
		)
		(fp_line
			(start 0.120396 0.2794)
			(end -0.12065 0.2794)
			(stroke
				(width 0.1)
				(type default)
			)
			(layer "F.Fab")
		)
		(fp_line
			(start -0.12065 0.2794)
			(end -0.12065 0.3048)
			(stroke
				(width 0.1)
				(type default)
			)
			(layer "F.Fab")
		)
		(fp_line
			(start 0.67945 0.3048)
			(end 0.120396 0.3048)
			(stroke
				(width 0.1)
				(type default)
			)
			(layer "F.Fab")
		)
		(fp_line
			(start 0.120396 0.3048)
			(end 0.120396 0.2794)
			(stroke
				(width 0.1)
				(type default)
			)
			(layer "F.Fab")
		)
		(fp_line
			(start -0.12065 0.3048)
			(end -0.67945 0.3048)
			(stroke
				(width 0.1)
				(type default)
			)
			(layer "F.Fab")
		)
		(fp_line
			(start -0.67945 0.3048)
			(end -0.67945 -0.305054)
			(stroke
				(width 0.1)
				(type default)
			)
			(layer "F.Fab")
		)
		(pad "1" smd circle
			(at -0.40005 0 90)
			(size 0 0)
			(layers "F.Cu" "F.Mask" "F.Paste")
			(net "PVDDCR_CPU1_P1")
		)
		(pad "2" smd circle
			(at 0.40005 0 90)
			(size 0 0)
			(layers "F.Cu" "F.Mask" "F.Paste")
			(net "GND")
		)
	)
	(footprint ""
		(layer "F.Cu")
		(at 352.135186 -428.406052 90)
		(property "Reference" "Q146"
			(at -1.2954 1.787652 90)
			(unlocked yes)
			(layer "F.SilkS")
			(effects
				(font
					(size 0.7874 0.5842)
					(thickness 0.1524)
				)
				(justify left)
			)
		)
		(property "Value" ""
			(at 0 0 90)
			(layer "F.Fab")
			(effects
				(font
					(size 1.27 1.27)
				)
			)
		)
		(duplicate_pad_numbers_are_jumpers no)
		(fp_line
			(start 1.332738 -1.100074)
			(end 1.332738 1.100074)
			(stroke
				(width 0.1524)
				(type default)
			)
			(layer "F.SilkS")
		)
		(fp_line
			(start 0.4826 -1.100074)
			(end 1.332738 -1.100074)
			(stroke
				(width 0.1524)
				(type default)
			)
			(layer "F.SilkS")
		)
		(fp_line
			(start -0.4826 -1.100074)
			(end 0 -0.541274)
			(stroke
				(width 0.1524)
				(type default)
			)
			(layer "F.SilkS")
		)
		(fp_line
			(start -1.332738 -1.100074)
			(end -0.4826 -1.100074)
			(stroke
				(width 0.1524)
				(type default)
			)
			(layer "F.SilkS")
		)
		(fp_line
			(start 0 -0.541274)
			(end 0.4826 -1.100074)
			(stroke
				(width 0.1524)
				(type default)
			)
			(layer "F.SilkS")
		)
		(fp_line
			(start 1.332738 1.100074)
			(end -1.332738 1.100074)
			(stroke
				(width 0.1524)
				(type default)
			)
			(layer "F.SilkS")
		)
		(fp_line
			(start -1.332738 1.100074)
			(end -1.332738 -1.100074)
			(stroke
				(width 0.1524)
				(type default)
			)
			(layer "F.SilkS")
		)
		(fp_poly
			(pts
				(xy -1.533144 -0.649986) (xy -2.2352 -0.298958) (xy -2.2352 -1.001014)
			)
			(stroke
				(width 0)
				(type default)
			)
			(fill yes)
			(layer "F.SilkS")
		)
		(fp_line
			(start 0.674878 -1.100074)
			(end 0.674878 1.100074)
			(stroke
				(width 0.1)
				(type default)
			)
			(layer "F.Fab")
		)
		(fp_line
			(start -0.674878 -1.100074)
			(end 0.674878 -1.100074)
			(stroke
				(width 0.1)
				(type default)
			)
			(layer "F.Fab")
		)
		(fp_line
			(start 0.674878 1.100074)
			(end -0.674878 1.100074)
			(stroke
				(width 0.1)
				(type default)
			)
			(layer "F.Fab")
		)
		(fp_line
			(start -0.674878 1.100074)
			(end -0.674878 -1.100074)
			(stroke
				(width 0.1)
				(type default)
			)
			(layer "F.Fab")
		)
		(fp_poly
			(pts
				(xy -2.2352 -0.298958) (xy -2.2352 -1.001014) (xy -1.533144 -0.649986)
			)
			(stroke
				(width 0)
				(type default)
			)
			(fill yes)
			(layer "F.Fab")
		)
		(pad "1" smd rect
			(at -0.94996 -0.649986 180)
			(size 0.4318 0.508)
			(layers "F.Cu" "F.Mask" "F.Paste")
			(net "GND")
		)
		(pad "2" smd rect
			(at -0.94996 0 180)
			(size 0.4318 0.508)
			(layers "F.Cu" "F.Mask" "F.Paste")
			(net "SWB_HSC_PWRGD")
		)
		(pad "3" smd rect
			(at -0.94996 0.649986 180)
			(size 0.4318 0.508)
			(layers "F.Cu" "F.Mask" "F.Paste")
			(net "SWB_HSC_PWRGD_ISO")
		)
		(pad "4" smd rect
			(at 0.94996 0.649986 180)
			(size 0.4318 0.508)
			(layers "F.Cu" "F.Mask" "F.Paste")
			(net "GND")
		)
		(pad "5" smd rect
			(at 0.94996 0 180)
			(size 0.4318 0.508)
			(layers "F.Cu" "F.Mask" "F.Paste")
			(net "SWB_HSC_PWRGD_N")
		)
		(pad "6" smd rect
			(at 0.94996 -0.649986 180)
			(size 0.4318 0.508)
			(layers "F.Cu" "F.Mask" "F.Paste")
			(net "SWB_HSC_PWRGD_N")
		)
	)
	(footprint ""
		(layer "F.Cu")
		(at 146.214846 -395.221206 -90)
		(property "Reference" "R884"
			(at 0 0 270)
			(layer "F.SilkS")
			(hide yes)
			(effects
				(font
					(size 1.27 1.27)
				)
			)
		)
		(property "Value" ""
			(at 0 0 270)
			(layer "F.Fab")
			(effects
				(font
					(size 1.27 1.27)
				)
			)
		)
		(duplicate_pad_numbers_are_jumpers no)
		(fp_line
			(start -0.32512 0.175006)
			(end -0.32512 -0.175006)
			(stroke
				(width 0.1)
				(type default)
			)
			(layer "F.Fab")
		)
		(fp_line
			(start 0.32512 0.175006)
			(end -0.32512 0.175006)
			(stroke
				(width 0.1)
				(type default)
			)
			(layer "F.Fab")
		)
		(fp_line
			(start -0.32512 -0.175006)
			(end 0.32512 -0.175006)
			(stroke
				(width 0.1)
				(type default)
			)
			(layer "F.Fab")
		)
		(fp_line
			(start 0.32512 -0.175006)
			(end 0.32512 0.175006)
			(stroke
				(width 0.1)
				(type default)
			)
			(layer "F.Fab")
		)
		(pad "1" smd rect
			(at -0.2667 0 270)
			(size 0.3048 0.381)
			(layers "F.Cu" "F.Mask" "F.Paste")
			(net "JTAG_TEST_MODE_RT_CPU1_P2")
		)
		(pad "2" smd rect
			(at 0.2667 0 90)
			(size 0.3048 0.381)
			(layers "F.Cu" "F.Mask" "F.Paste")
			(net "GND")
		)
	)
)
